(kicad_pcb
	(version 20260206)
	(generator "pcbnew")
	(generator_version "10.0")
	(general
		(thickness 1.6)
		(legacy_teardrops no)
	)
	(paper "A4")
	(title_block
		(title "04192023_DAF0TMB3IC0_F0TG_MB_C_brd_V02_OCP.brd")
		(comment 1 "Grand Teton / footprints 5971-5976 of 8354")
	)
	(layers
		(0 "F.Cu" signal "TOP")
		(4 "In1.Cu" signal "GND")
		(6 "In2.Cu" signal "IN1")
		(8 "In3.Cu" signal "GND1")
		(10 "In4.Cu" signal "IN2")
		(12 "In5.Cu" signal "GND2")
		(14 "In6.Cu" signal "IN3")
		(16 "In7.Cu" signal "GND3")
		(18 "In8.Cu" signal "VCC")
		(20 "In9.Cu" signal "VCC1")
		(22 "In10.Cu" signal "GND4")
		(24 "In11.Cu" signal "IN4")
		(26 "In12.Cu" signal "GND5")
		(28 "In13.Cu" signal "IN5")
		(30 "In14.Cu" signal "GND6")
		(32 "In15.Cu" signal "IN6")
		(34 "In16.Cu" signal "GND7")
		(2 "B.Cu" signal "BOTTOM")
		(9 "F.Adhes" user "F.Adhesive")
		(11 "B.Adhes" user "B.Adhesive")
		(13 "F.Paste" user "Package Geometry/Pastemask Top")
		(15 "B.Paste" user "Package Geometry/Pastemask Bottom")
		(5 "F.SilkS" user "Ref Des/Silkscreen Top")
		(7 "B.SilkS" user "Ref Des/Silkscreen Bottom")
		(1 "F.Mask" user "Board Geometry/Soldermask Top")
		(3 "B.Mask" user "Board Geometry/Soldermask Bottom")
		(17 "Dwgs.User" user "User.Drawings")
		(19 "Cmts.User" user "User.Comments")
		(21 "Eco1.User" user "User.Eco1")
		(23 "Eco2.User" user "User.Eco2")
		(25 "Edge.Cuts" user "Board Geometry/Outline")
		(27 "Margin" user)
		(31 "F.CrtYd" user "Package Geometry/Place Bound Top")
		(29 "B.CrtYd" user "Package Geometry/Place Bound Bottom")
		(35 "F.Fab" user "Ref Des/Assembly Top")
		(33 "B.Fab" user "Ref Des/Assembly Bottom")
	)
	(footprint ""
		(layer "B.Cu")
		(at 103.632 -415.925 -90)
		(property "Reference" "R4544"
			(at 0 0 90)
			(layer "B.SilkS")
			(hide yes)
			(effects
				(font
					(size 1.27 1.27)
				)
				(justify mirror)
			)
		)
		(property "Value" ""
			(at 0 0 90)
			(layer "B.Fab")
			(effects
				(font
					(size 1.27 1.27)
				)
				(justify mirror)
			)
		)
		(duplicate_pad_numbers_are_jumpers no)
		(fp_line
			(start -0.7874 0.4064)
			(end 0.7874 0.4064)
			(stroke
				(width 0.1524)
				(type default)
			)
			(layer "B.SilkS")
		)
		(fp_line
			(start 0.7874 0.4064)
			(end 0.7874 -0.4064)
			(stroke
				(width 0.1524)
				(type default)
			)
			(layer "B.SilkS")
		)
		(fp_line
			(start -0.7874 -0.4064)
			(end -0.7874 0.4064)
			(stroke
				(width 0.1524)
				(type default)
			)
			(layer "B.SilkS")
		)
		(fp_line
			(start 0.7874 -0.4064)
			(end -0.7874 -0.4064)
			(stroke
				(width 0.1524)
				(type default)
			)
			(layer "B.SilkS")
		)
		(fp_line
			(start -0.67945 0.3048)
			(end -0.120396 0.3048)
			(stroke
				(width 0.1)
				(type default)
			)
			(layer "B.Fab")
		)
		(fp_line
			(start -0.120396 0.3048)
			(end -0.120396 0.2794)
			(stroke
				(width 0.1)
				(type default)
			)
			(layer "B.Fab")
		)
		(fp_line
			(start 0.12065 0.3048)
			(end 0.67945 0.3048)
			(stroke
				(width 0.1)
				(type default)
			)
			(layer "B.Fab")
		)
		(fp_line
			(start 0.67945 0.3048)
			(end 0.67945 -0.305054)
			(stroke
				(width 0.1)
				(type default)
			)
			(layer "B.Fab")
		)
		(fp_line
			(start -0.120396 0.2794)
			(end 0.12065 0.2794)
			(stroke
				(width 0.1)
				(type default)
			)
			(layer "B.Fab")
		)
		(fp_line
			(start 0.12065 0.2794)
			(end 0.12065 0.3048)
			(stroke
				(width 0.1)
				(type default)
			)
			(layer "B.Fab")
		)
		(fp_line
			(start -0.12065 -0.2794)
			(end -0.12065 -0.3048)
			(stroke
				(width 0.1)
				(type default)
			)
			(layer "B.Fab")
		)
		(fp_line
			(start 0.12065 -0.2794)
			(end -0.12065 -0.2794)
			(stroke
				(width 0.1)
				(type default)
			)
			(layer "B.Fab")
		)
		(fp_line
			(start -0.67945 -0.3048)
			(end -0.67945 0.3048)
			(stroke
				(width 0.1)
				(type default)
			)
			(layer "B.Fab")
		)
		(fp_line
			(start -0.12065 -0.3048)
			(end -0.67945 -0.3048)
			(stroke
				(width 0.1)
				(type default)
			)
			(layer "B.Fab")
		)
		(fp_line
			(start 0.12065 -0.305054)
			(end 0.12065 -0.2794)
			(stroke
				(width 0.1)
				(type default)
			)
			(layer "B.Fab")
		)
		(fp_line
			(start 0.67945 -0.305054)
			(end 0.12065 -0.305054)
			(stroke
				(width 0.1)
				(type default)
			)
			(layer "B.Fab")
		)
		(pad "1" smd circle
			(at 0.40005 0 90)
			(size 0 0)
			(layers "B.Cu" "B.Mask" "B.Paste")
			(net "HGX_DETECT_N")
		)
		(pad "2" smd circle
			(at -0.40005 0 90)
			(size 0 0)
			(layers "B.Cu" "B.Mask" "B.Paste")
			(net "GND")
		)
	)
	(footprint ""
		(layer "B.Cu")
		(at 205.25105 -244.085364)
		(property "Reference" "R511"
			(at 0 0 0)
			(layer "B.SilkS")
			(hide yes)
			(effects
				(font
					(size 1.27 1.27)
				)
				(justify mirror)
			)
		)
		(property "Value" ""
			(at 0 0 0)
			(layer "B.Fab")
			(effects
				(font
					(size 1.27 1.27)
				)
				(justify mirror)
			)
		)
		(duplicate_pad_numbers_are_jumpers no)
		(fp_line
			(start -0.7874 -0.4064)
			(end -0.7874 0.4064)
			(stroke
				(width 0.1524)
				(type default)
			)
			(layer "B.SilkS")
		)
		(fp_line
			(start -0.7874 0.4064)
			(end 0.7874 0.4064)
			(stroke
				(width 0.1524)
				(type default)
			)
			(layer "B.SilkS")
		)
		(fp_line
			(start 0.7874 -0.4064)
			(end -0.7874 -0.4064)
			(stroke
				(width 0.1524)
				(type default)
			)
			(layer "B.SilkS")
		)
		(fp_line
			(start 0.7874 0.4064)
			(end 0.7874 -0.4064)
			(stroke
				(width 0.1524)
				(type default)
			)
			(layer "B.SilkS")
		)
		(fp_line
			(start -0.67945 -0.3048)
			(end -0.67945 0.3048)
			(stroke
				(width 0.1)
				(type default)
			)
			(layer "B.Fab")
		)
		(fp_line
			(start -0.67945 0.3048)
			(end -0.120396 0.3048)
			(stroke
				(width 0.1)
				(type default)
			)
			(layer "B.Fab")
		)
		(fp_line
			(start -0.12065 -0.3048)
			(end -0.67945 -0.3048)
			(stroke
				(width 0.1)
				(type default)
			)
			(layer "B.Fab")
		)
		(fp_line
			(start -0.12065 -0.2794)
			(end -0.12065 -0.3048)
			(stroke
				(width 0.1)
				(type default)
			)
			(layer "B.Fab")
		)
		(fp_line
			(start -0.120396 0.2794)
			(end 0.12065 0.2794)
			(stroke
				(width 0.1)
				(type default)
			)
			(layer "B.Fab")
		)
		(fp_line
			(start -0.120396 0.3048)
			(end -0.120396 0.2794)
			(stroke
				(width 0.1)
				(type default)
			)
			(layer "B.Fab")
		)
		(fp_line
			(start 0.12065 -0.305054)
			(end 0.12065 -0.2794)
			(stroke
				(width 0.1)
				(type default)
			)
			(layer "B.Fab")
		)
		(fp_line
			(start 0.12065 -0.2794)
			(end -0.12065 -0.2794)
			(stroke
				(width 0.1)
				(type default)
			)
			(layer "B.Fab")
		)
		(fp_line
			(start 0.12065 0.2794)
			(end 0.12065 0.3048)
			(stroke
				(width 0.1)
				(type default)
			)
			(layer "B.Fab")
		)
		(fp_line
			(start 0.12065 0.3048)
			(end 0.67945 0.3048)
			(stroke
				(width 0.1)
				(type default)
			)
			(layer "B.Fab")
		)
		(fp_line
			(start 0.67945 -0.305054)
			(end 0.12065 -0.305054)
			(stroke
				(width 0.1)
				(type default)
			)
			(layer "B.Fab")
		)
		(fp_line
			(start 0.67945 0.3048)
			(end 0.67945 -0.305054)
			(stroke
				(width 0.1)
				(type default)
			)
			(layer "B.Fab")
		)
		(pad "1" smd circle
			(at 0.40005 0 180)
			(size 0 0)
			(layers "B.Cu" "B.Mask" "B.Paste")
			(net "M_L_CPU1_ALERT_N")
		)
		(pad "2" smd circle
			(at -0.40005 0 180)
			(size 0 0)
			(layers "B.Cu" "B.Mask" "B.Paste")
			(net "M_L_CPU1_ALERT_R_N")
		)
	)
	(footprint ""
		(layer "B.Cu")
		(at 121.706386 -249.368564)
		(property "Reference" "C2325"
			(at 0 0 0)
			(layer "B.SilkS")
			(hide yes)
			(effects
				(font
					(size 1.27 1.27)
				)
				(justify mirror)
			)
		)
		(property "Value" ""
			(at 0 0 0)
			(layer "B.Fab")
			(effects
				(font
					(size 1.27 1.27)
				)
				(justify mirror)
			)
		)
		(duplicate_pad_numbers_are_jumpers no)
		(fp_line
			(start -0.7874 -0.4064)
			(end -0.7874 0.4064)
			(stroke
				(width 0.1524)
				(type default)
			)
			(layer "B.SilkS")
		)
		(fp_line
			(start -0.7874 0.4064)
			(end 0.7874 0.4064)
			(stroke
				(width 0.1524)
				(type default)
			)
			(layer "B.SilkS")
		)
		(fp_line
			(start 0.7874 -0.4064)
			(end -0.7874 -0.4064)
			(stroke
				(width 0.1524)
				(type default)
			)
			(layer "B.SilkS")
		)
		(fp_line
			(start 0.7874 0.4064)
			(end 0.7874 -0.4064)
			(stroke
				(width 0.1524)
				(type default)
			)
			(layer "B.SilkS")
		)
		(fp_line
			(start -0.67945 -0.3048)
			(end -0.67945 0.3048)
			(stroke
				(width 0.1)
				(type default)
			)
			(layer "B.Fab")
		)
		(fp_line
			(start -0.67945 0.3048)
			(end -0.120396 0.3048)
			(stroke
				(width 0.1)
				(type default)
			)
			(layer "B.Fab")
		)
		(fp_line
			(start -0.12065 -0.3048)
			(end -0.67945 -0.3048)
			(stroke
				(width 0.1)
				(type default)
			)
			(layer "B.Fab")
		)
		(fp_line
			(start -0.12065 -0.2794)
			(end -0.12065 -0.3048)
			(stroke
				(width 0.1)
				(type default)
			)
			(layer "B.Fab")
		)
		(fp_line
			(start -0.120396 0.2794)
			(end 0.12065 0.2794)
			(stroke
				(width 0.1)
				(type default)
			)
			(layer "B.Fab")
		)
		(fp_line
			(start -0.120396 0.3048)
			(end -0.120396 0.2794)
			(stroke
				(width 0.1)
				(type default)
			)
			(layer "B.Fab")
		)
		(fp_line
			(start 0.12065 -0.305054)
			(end 0.12065 -0.2794)
			(stroke
				(width 0.1)
				(type default)
			)
			(layer "B.Fab")
		)
		(fp_line
			(start 0.12065 -0.2794)
			(end -0.12065 -0.2794)
			(stroke
				(width 0.1)
				(type default)
			)
			(layer "B.Fab")
		)
		(fp_line
			(start 0.12065 0.2794)
			(end 0.12065 0.3048)
			(stroke
				(width 0.1)
				(type default)
			)
			(layer "B.Fab")
		)
		(fp_line
			(start 0.12065 0.3048)
			(end 0.67945 0.3048)
			(stroke
				(width 0.1)
				(type default)
			)
			(layer "B.Fab")
		)
		(fp_line
			(start 0.67945 -0.305054)
			(end 0.12065 -0.305054)
			(stroke
				(width 0.1)
				(type default)
			)
			(layer "B.Fab")
		)
		(fp_line
			(start 0.67945 0.3048)
			(end 0.67945 -0.305054)
			(stroke
				(width 0.1)
				(type default)
			)
			(layer "B.Fab")
		)
		(pad "1" smd circle
			(at 0.40005 0 180)
			(size 0 0)
			(layers "B.Cu" "B.Mask" "B.Paste")
			(net "PVDDCR_CPU0_P1")
		)
		(pad "2" smd circle
			(at -0.40005 0 180)
			(size 0 0)
			(layers "B.Cu" "B.Mask" "B.Paste")
			(net "GND")
		)
	)
	(footprint ""
		(layer "B.Cu")
		(at 131.849114 -31.421578 -90)
		(property "Reference" "C6051"
			(at 0 0 90)
			(layer "B.SilkS")
			(hide yes)
			(effects
				(font
					(size 1.27 1.27)
				)
				(justify mirror)
			)
		)
		(property "Value" ""
			(at 0 0 90)
			(layer "B.Fab")
			(effects
				(font
					(size 1.27 1.27)
				)
				(justify mirror)
			)
		)
		(duplicate_pad_numbers_are_jumpers no)
		(fp_line
			(start -0.7874 0.4064)
			(end 0.7874 0.4064)
			(stroke
				(width 0.1524)
				(type default)
			)
			(layer "B.SilkS")
		)
		(fp_line
			(start 0.7874 0.4064)
			(end 0.7874 -0.4064)
			(stroke
				(width 0.1524)
				(type default)
			)
			(layer "B.SilkS")
		)
		(fp_line
			(start -0.7874 -0.4064)
			(end -0.7874 0.4064)
			(stroke
				(width 0.1524)
				(type default)
			)
			(layer "B.SilkS")
		)
		(fp_line
			(start 0.7874 -0.4064)
			(end -0.7874 -0.4064)
			(stroke
				(width 0.1524)
				(type default)
			)
			(layer "B.SilkS")
		)
		(fp_line
			(start -0.67945 0.3048)
			(end -0.120396 0.3048)
			(stroke
				(width 0.1)
				(type default)
			)
			(layer "B.Fab")
		)
		(fp_line
			(start -0.120396 0.3048)
			(end -0.120396 0.2794)
			(stroke
				(width 0.1)
				(type default)
			)
			(layer "B.Fab")
		)
		(fp_line
			(start 0.12065 0.3048)
			(end 0.67945 0.3048)
			(stroke
				(width 0.1)
				(type default)
			)
			(layer "B.Fab")
		)
		(fp_line
			(start 0.67945 0.3048)
			(end 0.67945 -0.305054)
			(stroke
				(width 0.1)
				(type default)
			)
			(layer "B.Fab")
		)
		(fp_line
			(start -0.120396 0.2794)
			(end 0.12065 0.2794)
			(stroke
				(width 0.1)
				(type default)
			)
			(layer "B.Fab")
		)
		(fp_line
			(start 0.12065 0.2794)
			(end 0.12065 0.3048)
			(stroke
				(width 0.1)
				(type default)
			)
			(layer "B.Fab")
		)
		(fp_line
			(start -0.12065 -0.2794)
			(end -0.12065 -0.3048)
			(stroke
				(width 0.1)
				(type default)
			)
			(layer "B.Fab")
		)
		(fp_line
			(start 0.12065 -0.2794)
			(end -0.12065 -0.2794)
			(stroke
				(width 0.1)
				(type default)
			)
			(layer "B.Fab")
		)
		(fp_line
			(start -0.67945 -0.3048)
			(end -0.67945 0.3048)
			(stroke
				(width 0.1)
				(type default)
			)
			(layer "B.Fab")
		)
		(fp_line
			(start -0.12065 -0.3048)
			(end -0.67945 -0.3048)
			(stroke
				(width 0.1)
				(type default)
			)
			(layer "B.Fab")
		)
		(fp_line
			(start 0.12065 -0.305054)
			(end 0.12065 -0.2794)
			(stroke
				(width 0.1)
				(type default)
			)
			(layer "B.Fab")
		)
		(fp_line
			(start 0.67945 -0.305054)
			(end 0.12065 -0.305054)
			(stroke
				(width 0.1)
				(type default)
			)
			(layer "B.Fab")
		)
		(pad "1" smd circle
			(at 0.40005 0 90)
			(size 0 0)
			(layers "B.Cu" "B.Mask" "B.Paste")
			(net "P3V3_AUX")
		)
		(pad "2" smd circle
			(at -0.40005 0 90)
			(size 0 0)
			(layers "B.Cu" "B.Mask" "B.Paste")
			(net "GND")
		)
	)
	(footprint ""
		(layer "B.Cu")
		(at 359.721404 -253.43231 180)
		(property "Reference" "C2144"
			(at 0 0 0)
			(layer "B.SilkS")
			(hide yes)
			(effects
				(font
					(size 1.27 1.27)
				)
				(justify mirror)
			)
		)
		(property "Value" ""
			(at 0 0 0)
			(layer "B.Fab")
			(effects
				(font
					(size 1.27 1.27)
				)
				(justify mirror)
			)
		)
		(duplicate_pad_numbers_are_jumpers no)
		(fp_line
			(start 0.7874 0.4064)
			(end 0.7874 -0.4064)
			(stroke
				(width 0.1524)
				(type default)
			)
			(layer "B.SilkS")
		)
		(fp_line
			(start 0.7874 -0.4064)
			(end -0.7874 -0.4064)
			(stroke
				(width 0.1524)
				(type default)
			)
			(layer "B.SilkS")
		)
		(fp_line
			(start -0.7874 0.4064)
			(end 0.7874 0.4064)
			(stroke
				(width 0.1524)
				(type default)
			)
			(layer "B.SilkS")
		)
		(fp_line
			(start -0.7874 -0.4064)
			(end -0.7874 0.4064)
			(stroke
				(width 0.1524)
				(type default)
			)
			(layer "B.SilkS")
		)
		(fp_line
			(start 0.67945 0.3048)
			(end 0.67945 -0.305054)
			(stroke
				(width 0.1)
				(type default)
			)
			(layer "B.Fab")
		)
		(fp_line
			(start 0.67945 -0.305054)
			(end 0.12065 -0.305054)
			(stroke
				(width 0.1)
				(type default)
			)
			(layer "B.Fab")
		)
		(fp_line
			(start 0.12065 0.3048)
			(end 0.67945 0.3048)
			(stroke
				(width 0.1)
				(type default)
			)
			(layer "B.Fab")
		)
		(fp_line
			(start 0.12065 0.2794)
			(end 0.12065 0.3048)
			(stroke
				(width 0.1)
				(type default)
			)
			(layer "B.Fab")
		)
		(fp_line
			(start 0.12065 -0.2794)
			(end -0.12065 -0.2794)
			(stroke
				(width 0.1)
				(type default)
			)
			(layer "B.Fab")
		)
		(fp_line
			(start 0.12065 -0.305054)
			(end 0.12065 -0.2794)
			(stroke
				(width 0.1)
				(type default)
			)
			(layer "B.Fab")
		)
		(fp_line
			(start -0.120396 0.3048)
			(end -0.120396 0.2794)
			(stroke
				(width 0.1)
				(type default)
			)
			(layer "B.Fab")
		)
		(fp_line
			(start -0.120396 0.2794)
			(end 0.12065 0.2794)
			(stroke
				(width 0.1)
				(type default)
			)
			(layer "B.Fab")
		)
		(fp_line
			(start -0.12065 -0.2794)
			(end -0.12065 -0.3048)
			(stroke
				(width 0.1)
				(type default)
			)
			(layer "B.Fab")
		)
		(fp_line
			(start -0.12065 -0.3048)
			(end -0.67945 -0.3048)
			(stroke
				(width 0.1)
				(type default)
			)
			(layer "B.Fab")
		)
		(fp_line
			(start -0.67945 0.3048)
			(end -0.120396 0.3048)
			(stroke
				(width 0.1)
				(type default)
			)
			(layer "B.Fab")
		)
		(fp_line
			(start -0.67945 -0.3048)
			(end -0.67945 0.3048)
			(stroke
				(width 0.1)
				(type default)
			)
			(layer "B.Fab")
		)
		(pad "1" smd circle
			(at 0.40005 0)
			(size 0 0)
			(layers "B.Cu" "B.Mask" "B.Paste")
			(net "PVDDCR_SOC_P0")
		)
		(pad "2" smd circle
			(at -0.40005 0)
			(size 0 0)
			(layers "B.Cu" "B.Mask" "B.Paste")
			(net "GND")
		)
	)
	(footprint ""
		(layer "B.Cu")
		(at 100.271834 -263.521952)
		(property "Reference" "C2105"
			(at 0 0 0)
			(layer "B.SilkS")
			(hide yes)
			(effects
				(font
					(size 1.27 1.27)
				)
				(justify mirror)
			)
		)
		(property "Value" ""
			(at 0 0 0)
			(layer "B.Fab")
			(effects
				(font
					(size 1.27 1.27)
				)
				(justify mirror)
			)
		)
		(duplicate_pad_numbers_are_jumpers no)
		(fp_line
			(start -0.7874 -0.4064)
			(end -0.7874 0.4064)
			(stroke
				(width 0.1524)
				(type default)
			)
			(layer "B.SilkS")
		)
		(fp_line
			(start -0.7874 0.4064)
			(end 0.7874 0.4064)
			(stroke
				(width 0.1524)
				(type default)
			)
			(layer "B.SilkS")
		)
		(fp_line
			(start 0.7874 -0.4064)
			(end -0.7874 -0.4064)
			(stroke
				(width 0.1524)
				(type default)
			)
			(layer "B.SilkS")
		)
		(fp_line
			(start 0.7874 0.4064)
			(end 0.7874 -0.4064)
			(stroke
				(width 0.1524)
				(type default)
			)
			(layer "B.SilkS")
		)
		(fp_line
			(start -0.67945 -0.3048)
			(end -0.67945 0.3048)
			(stroke
				(width 0.1)
				(type default)
			)
			(layer "B.Fab")
		)
		(fp_line
			(start -0.67945 0.3048)
			(end -0.120396 0.3048)
			(stroke
				(width 0.1)
				(type default)
			)
			(layer "B.Fab")
		)
		(fp_line
			(start -0.12065 -0.3048)
			(end -0.67945 -0.3048)
			(stroke
				(width 0.1)
				(type default)
			)
			(layer "B.Fab")
		)
		(fp_line
			(start -0.12065 -0.2794)
			(end -0.12065 -0.3048)
			(stroke
				(width 0.1)
				(type default)
			)
			(layer "B.Fab")
		)
		(fp_line
			(start -0.120396 0.2794)
			(end 0.12065 0.2794)
			(stroke
				(width 0.1)
				(type default)
			)
			(layer "B.Fab")
		)
		(fp_line
			(start -0.120396 0.3048)
			(end -0.120396 0.2794)
			(stroke
				(width 0.1)
				(type default)
			)
			(layer "B.Fab")
		)
		(fp_line
			(start 0.12065 -0.305054)
			(end 0.12065 -0.2794)
			(stroke
				(width 0.1)
				(type default)
			)
			(layer "B.Fab")
		)
		(fp_line
			(start 0.12065 -0.2794)
			(end -0.12065 -0.2794)
			(stroke
				(width 0.1)
				(type default)
			)
			(layer "B.Fab")
		)
		(fp_line
			(start 0.12065 0.2794)
			(end 0.12065 0.3048)
			(stroke
				(width 0.1)
				(type default)
			)
			(layer "B.Fab")
		)
		(fp_line
			(start 0.12065 0.3048)
			(end 0.67945 0.3048)
			(stroke
				(width 0.1)
				(type default)
			)
			(layer "B.Fab")
		)
		(fp_line
			(start 0.67945 -0.305054)
			(end 0.12065 -0.305054)
			(stroke
				(width 0.1)
				(type default)
			)
			(layer "B.Fab")
		)
		(fp_line
			(start 0.67945 0.3048)
			(end 0.67945 -0.305054)
			(stroke
				(width 0.1)
				(type default)
			)
			(layer "B.Fab")
		)
		(pad "1" smd circle
			(at 0.40005 0 180)
			(size 0 0)
			(layers "B.Cu" "B.Mask" "B.Paste")
			(net "PVDDIO_P1")
		)
		(pad "2" smd circle
			(at -0.40005 0 180)
			(size 0 0)
			(layers "B.Cu" "B.Mask" "B.Paste")
			(net "GND")
		)
	)
)
